# BASEBOARD_FAB2 (Tioga Pass) — schematic netlist excerpt (pin names and nets, part order shuffled) for the footprints in the layout excerpt that follows; sources: Cadence DE-HDL packaged netlist, KiCad conversion of Wiwynn_Tioga_Pass_MB.brd

C7F16  CAP_A  1.0UF 6.3V 10% X6S  pkg 0402V  page 215 : A = VR_PVDDQ_ABC_VD12 ; B = GND
R3D27  RES  249 0.1% CHIP  pkg 0402  page 71 : A = VSENSE_PMAX_CPU1 ; B = GND
C9E11  CAP  1.0UF 16V 10% X6S  pkg 0402  page 238 : A = P3V3_STBY ; B = GND

(kicad_pcb
	(version 20260206)
	(generator "pcbnew")
	(generator_version "10.0")
	(general
		(thickness 1.6)
		(legacy_teardrops no)
	)
	(paper "A4")
	(title_block
		(title "Wiwynn_Tioga_Pass_MB.brd")
		(comment 1 "Tioga Pass / footprints 2066-2068 of 4770")
	)
	(layers
		(0 "F.Cu" signal "TOP")
		(4 "In1.Cu" signal "L2GND")
		(6 "In2.Cu" signal "L3")
		(8 "In3.Cu" signal "L4GND")
		(10 "In4.Cu" signal "L5")
		(12 "In5.Cu" signal "L6GND")
		(14 "In6.Cu" signal "L7VCC")
		(16 "In7.Cu" signal "L8VCC")
		(18 "In8.Cu" signal "L9GND")
		(20 "In9.Cu" signal "L10")
		(22 "In10.Cu" signal "L11GND")
		(24 "In11.Cu" signal "L12")
		(26 "In12.Cu" signal "L13GND")
		(2 "B.Cu" signal "BOTTOM")
		(9 "F.Adhes" user "F.Adhesive")
		(11 "B.Adhes" user "B.Adhesive")
		(13 "F.Paste" user "Package Geometry/Pastemask Top")
		(15 "B.Paste" user "Package Geometry/Pastemask Bottom")
		(5 "F.SilkS" user "Ref Des/Silkscreen Top")
		(7 "B.SilkS" user "Ref Des/Silkscreen Bottom")
		(1 "F.Mask" user "Board Geometry/Soldermask Top")
		(3 "B.Mask" user "Board Geometry/Soldermask Bottom")
		(17 "Dwgs.User" user "User.Drawings")
		(19 "Cmts.User" user "User.Comments")
		(21 "Eco1.User" user "User.Eco1")
		(23 "Eco2.User" user "User.Eco2")
		(25 "Edge.Cuts" user "Board Geometry/Outline")
		(27 "Margin" user)
		(31 "F.CrtYd" user "Package Geometry/Place Bound Top")
		(29 "B.CrtYd" user "Package Geometry/Place Bound Bottom")
		(35 "F.Fab" user "Ref Des/Assembly Top")
		(33 "B.Fab" user "Ref Des/Assembly Bottom")
	)
	(footprint ""
		(layer "F.Cu")
		(at 108.839 -68.072 90)
		(property "Reference" "R3D27"
			(at 0 0 90)
			(layer "F.SilkS")
			(hide yes)
			(effects
				(font
					(size 1.27 1.27)
				)
			)
		)
		(property "Value" ""
			(at 0 0 90)
			(layer "F.Fab")
			(effects
				(font
					(size 1.27 1.27)
				)
			)
		)
		(duplicate_pad_numbers_are_jumpers no)
		(fp_poly
			(pts
				(xy -0.2794 -0.1016) (xy 0.2794 -0.1016) (xy 0.2794 0.9906) (xy -0.2794 0.9906)
			)
			(stroke
				(width 0)
				(type default)
			)
			(fill no)
			(layer "F.CrtYd")
		)
		(fp_line
			(start 0.2794 -0.1016)
			(end -0.2794 -0.1016)
			(stroke
				(width 0.1)
				(type default)
			)
			(layer "F.Fab")
		)
		(fp_line
			(start -0.2794 -0.1016)
			(end -0.2794 0.9906)
			(stroke
				(width 0.1)
				(type default)
			)
			(layer "F.Fab")
		)
		(fp_line
			(start 0.2794 0.9906)
			(end 0.2794 -0.1016)
			(stroke
				(width 0.1)
				(type default)
			)
			(layer "F.Fab")
		)
		(fp_line
			(start -0.2794 0.9906)
			(end 0.2794 0.9906)
			(stroke
				(width 0.1)
				(type default)
			)
			(layer "F.Fab")
		)
		(pad "1" smd rect
			(at 0 0 90)
			(size 0.508 0.508)
			(layers "F.Cu" "F.Mask" "F.Paste")
			(net "VSENSE_PMAX_CPU1")
		)
		(pad "2" smd rect
			(at 0 0.889 90)
			(size 0.508 0.508)
			(layers "F.Cu" "F.Mask" "F.Paste")
			(net "GND")
		)
		(zone
			(layer "F.Cu")
			(hatch none 0.5)
			(connect_pads
				(clearance 0)
			)
			(min_thickness 0.25)
			(keepout
				(tracks allowed)
				(vias not_allowed)
				(pads allowed)
				(copperpour not_allowed)
				(footprints allowed)
			)
			(placement
				(enabled no)
				(sheetname "")
			)
			(fill
				(thermal_gap 0.5)
				(thermal_bridge_width 0.5)
				(island_removal_mode 0)
			)
			(polygon
				(pts
					(xy 109.093 -67.818) (xy 109.093 -68.326) (xy 109.474 -68.326) (xy 109.474 -67.818)
				)
			)
		)
		(zone
			(layer "F.Cu")
			(hatch none 0.5)
			(connect_pads
				(clearance 0)
			)
			(min_thickness 0.25)
			(keepout
				(tracks not_allowed)
				(vias allowed)
				(pads allowed)
				(copperpour not_allowed)
				(footprints allowed)
			)
			(placement
				(enabled no)
				(sheetname "")
			)
			(fill
				(thermal_gap 0.5)
				(thermal_bridge_width 0.5)
				(island_removal_mode 0)
			)
			(polygon
				(pts
					(xy 109.474 -67.818) (xy 109.474 -68.326) (xy 109.093 -68.326) (xy 109.093 -67.818)
				)
			)
		)
	)
	(footprint ""
		(layer "F.Cu")
		(at 348.0054 -19.304 180)
		(property "Reference" "C7F16"
			(at 0 0 180)
			(layer "F.SilkS")
			(hide yes)
			(effects
				(font
					(size 1.27 1.27)
				)
			)
		)
		(property "Value" ""
			(at 0 0 180)
			(layer "F.Fab")
			(effects
				(font
					(size 1.27 1.27)
				)
			)
		)
		(duplicate_pad_numbers_are_jumpers no)
		(fp_poly
			(pts
				(xy 0.3048 -0.1016) (xy 0.3048 0.9906) (xy -0.3048 0.9906) (xy -0.3048 -0.1016)
			)
			(stroke
				(width 0)
				(type default)
			)
			(fill no)
			(layer "F.CrtYd")
		)
		(fp_line
			(start 0.3048 0.9906)
			(end 0.3048 -0.1016)
			(stroke
				(width 0.1)
				(type default)
			)
			(layer "F.Fab")
		)
		(fp_line
			(start 0.3048 -0.1016)
			(end -0.3048 -0.1016)
			(stroke
				(width 0.1)
				(type default)
			)
			(layer "F.Fab")
		)
		(fp_line
			(start -0.3048 0.9906)
			(end 0.3048 0.9906)
			(stroke
				(width 0.1)
				(type default)
			)
			(layer "F.Fab")
		)
		(fp_line
			(start -0.3048 -0.1016)
			(end -0.3048 0.9906)
			(stroke
				(width 0.1)
				(type default)
			)
			(layer "F.Fab")
		)
		(pad "1" smd rect
			(at 0 0 180)
			(size 0.508 0.508)
			(layers "F.Cu" "F.Mask" "F.Paste")
			(net "VR_PVDDQ_ABC_VD12")
		)
		(pad "2" smd rect
			(at 0 0.889 180)
			(size 0.508 0.508)
			(layers "F.Cu" "F.Mask" "F.Paste")
			(net "GND")
		)
		(zone
			(layer "F.Cu")
			(hatch none 0.5)
			(connect_pads
				(clearance 0)
			)
			(min_thickness 0.25)
			(keepout
				(tracks not_allowed)
				(vias allowed)
				(pads allowed)
				(copperpour not_allowed)
				(footprints allowed)
			)
			(placement
				(enabled no)
				(sheetname "")
			)
			(fill
				(thermal_gap 0.5)
				(thermal_bridge_width 0.5)
				(island_removal_mode 0)
			)
			(polygon
				(pts
					(xy 348.2594 -19.939) (xy 347.7514 -19.939) (xy 347.7514 -19.558) (xy 348.2594 -19.558)
				)
			)
		)
		(zone
			(layer "F.Cu")
			(hatch none 0.5)
			(connect_pads
				(clearance 0)
			)
			(min_thickness 0.25)
			(keepout
				(tracks allowed)
				(vias not_allowed)
				(pads allowed)
				(copperpour not_allowed)
				(footprints allowed)
			)
			(placement
				(enabled no)
				(sheetname "")
			)
			(fill
				(thermal_gap 0.5)
				(thermal_bridge_width 0.5)
				(island_removal_mode 0)
			)
			(polygon
				(pts
					(xy 348.2594 -19.558) (xy 347.7514 -19.558) (xy 347.7514 -19.939) (xy 348.2594 -19.939)
				)
			)
		)
	)
	(footprint ""
		(layer "F.Cu")
		(at 466.344 -41.0972)
		(property "Reference" "C9E11"
			(at 0 0 0)
			(layer "F.SilkS")
			(hide yes)
			(effects
				(font
					(size 1.27 1.27)
				)
			)
		)
		(property "Value" ""
			(at 0 0 0)
			(layer "F.Fab")
			(effects
				(font
					(size 1.27 1.27)
				)
			)
		)
		(duplicate_pad_numbers_are_jumpers no)
		(fp_poly
			(pts
				(xy 0.3048 -0.1016) (xy 0.3048 0.9906) (xy -0.3048 0.9906) (xy -0.3048 -0.1016)
			)
			(stroke
				(width 0)
				(type default)
			)
			(fill no)
			(layer "F.CrtYd")
		)
		(fp_line
			(start -0.3048 -0.1016)
			(end -0.3048 0.9906)
			(stroke
				(width 0.1)
				(type default)
			)
			(layer "F.Fab")
		)
		(fp_line
			(start -0.3048 0.9906)
			(end 0.3048 0.9906)
			(stroke
				(width 0.1)
				(type default)
			)
			(layer "F.Fab")
		)
		(fp_line
			(start 0.3048 -0.1016)
			(end -0.3048 -0.1016)
			(stroke
				(width 0.1)
				(type default)
			)
			(layer "F.Fab")
		)
		(fp_line
			(start 0.3048 0.9906)
			(end 0.3048 -0.1016)
			(stroke
				(width 0.1)
				(type default)
			)
			(layer "F.Fab")
		)
		(pad "1" smd rect
			(at 0 0)
			(size 0.508 0.508)
			(layers "F.Cu" "F.Mask" "F.Paste")
			(net "P3V3_STBY")
		)
		(pad "2" smd rect
			(at 0 0.889)
			(size 0.508 0.508)
			(layers "F.Cu" "F.Mask" "F.Paste")
			(net "GND")
		)
		(zone
			(layer "F.Cu")
			(hatch none 0.5)
			(connect_pads
				(clearance 0)
			)
			(min_thickness 0.25)
			(keepout
				(tracks allowed)
				(vias not_allowed)
				(pads allowed)
				(copperpour not_allowed)
				(footprints allowed)
			)
			(placement
				(enabled no)
				(sheetname "")
			)
			(fill
				(thermal_gap 0.5)
				(thermal_bridge_width 0.5)
				(island_removal_mode 0)
			)
			(polygon
				(pts
					(xy 466.09 -40.8432) (xy 466.598 -40.8432) (xy 466.598 -40.4622) (xy 466.09 -40.4622)
				)
			)
		)
		(zone
			(layer "F.Cu")
			(hatch none 0.5)
			(connect_pads
				(clearance 0)
			)
			(min_thickness 0.25)
			(keepout
				(tracks not_allowed)
				(vias allowed)
				(pads allowed)
				(copperpour not_allowed)
				(footprints allowed)
			)
			(placement
				(enabled no)
				(sheetname "")
			)
			(fill
				(thermal_gap 0.5)
				(thermal_bridge_width 0.5)
				(island_removal_mode 0)
			)
			(polygon
				(pts
					(xy 466.09 -40.4622) (xy 466.598 -40.4622) (xy 466.598 -40.8432) (xy 466.09 -40.8432)
				)
			)
		)
	)
)
